# T6G (Grand Teton) — schematic netlist excerpt (pin names and nets, part order shuffled) for the footprints in the layout excerpt that follows; sources: Cadence DE-HDL packaged netlist, KiCad conversion of 04192023_DAF0TMB3IC0_F0TG_MB_C_brd_V02_OCP.brd

R3166  Q_RES  4.7K 1% EMPTY  pkg 0402LF  page 137 : A = P3V3_OCP_V3_2 ; B = OCP_V3_2_ID1
PR3931  Q_RES  75K 0.1% CHIP  pkg 0402LF  page 262 : A = P12V_AUX ; B = HSC_VOSEN

(kicad_pcb
	(version 20260206)
	(generator "pcbnew")
	(generator_version "10.0")
	(general
		(thickness 1.6)
		(legacy_teardrops no)
	)
	(paper "A4")
	(title_block
		(title "04192023_DAF0TMB3IC0_F0TG_MB_C_brd_V02_OCP.brd")
		(comment 1 "Grand Teton / footprints 6949-6950 of 8354")
	)
	(layers
		(0 "F.Cu" signal "TOP")
		(4 "In1.Cu" signal "GND")
		(6 "In2.Cu" signal "IN1")
		(8 "In3.Cu" signal "GND1")
		(10 "In4.Cu" signal "IN2")
		(12 "In5.Cu" signal "GND2")
		(14 "In6.Cu" signal "IN3")
		(16 "In7.Cu" signal "GND3")
		(18 "In8.Cu" signal "VCC")
		(20 "In9.Cu" signal "VCC1")
		(22 "In10.Cu" signal "GND4")
		(24 "In11.Cu" signal "IN4")
		(26 "In12.Cu" signal "GND5")
		(28 "In13.Cu" signal "IN5")
		(30 "In14.Cu" signal "GND6")
		(32 "In15.Cu" signal "IN6")
		(34 "In16.Cu" signal "GND7")
		(2 "B.Cu" signal "BOTTOM")
		(9 "F.Adhes" user "F.Adhesive")
		(11 "B.Adhes" user "B.Adhesive")
		(13 "F.Paste" user "Package Geometry/Pastemask Top")
		(15 "B.Paste" user "Package Geometry/Pastemask Bottom")
		(5 "F.SilkS" user "Ref Des/Silkscreen Top")
		(7 "B.SilkS" user "Ref Des/Silkscreen Bottom")
		(1 "F.Mask" user "Board Geometry/Soldermask Top")
		(3 "B.Mask" user "Board Geometry/Soldermask Bottom")
		(17 "Dwgs.User" user "User.Drawings")
		(19 "Cmts.User" user "User.Comments")
		(21 "Eco1.User" user "User.Eco1")
		(23 "Eco2.User" user "User.Eco2")
		(25 "Edge.Cuts" user "Board Geometry/Outline")
		(27 "Margin" user)
		(31 "F.CrtYd" user "Package Geometry/Place Bound Top")
		(29 "B.CrtYd" user "Package Geometry/Place Bound Bottom")
		(35 "F.Fab" user "Ref Des/Assembly Top")
		(33 "B.Fab" user "Ref Des/Assembly Bottom")
	)
	(footprint ""
		(layer "B.Cu")
		(at 184.3405 -397.848582)
		(property "Reference" "PR3931"
			(at 0 0 0)
			(layer "B.SilkS")
			(hide yes)
			(effects
				(font
					(size 1.27 1.27)
				)
				(justify mirror)
			)
		)
		(property "Value" ""
			(at 0 0 0)
			(layer "B.Fab")
			(effects
				(font
					(size 1.27 1.27)
				)
				(justify mirror)
			)
		)
		(duplicate_pad_numbers_are_jumpers no)
		(fp_line
			(start -0.7874 -0.4064)
			(end -0.7874 0.4064)
			(stroke
				(width 0.1524)
				(type default)
			)
			(layer "B.SilkS")
		)
		(fp_line
			(start -0.7874 0.4064)
			(end 0.7874 0.4064)
			(stroke
				(width 0.1524)
				(type default)
			)
			(layer "B.SilkS")
		)
		(fp_line
			(start 0.7874 -0.4064)
			(end -0.7874 -0.4064)
			(stroke
				(width 0.1524)
				(type default)
			)
			(layer "B.SilkS")
		)
		(fp_line
			(start 0.7874 0.4064)
			(end 0.7874 -0.4064)
			(stroke
				(width 0.1524)
				(type default)
			)
			(layer "B.SilkS")
		)
		(fp_line
			(start -0.67945 -0.3048)
			(end -0.67945 0.3048)
			(stroke
				(width 0.1)
				(type default)
			)
			(layer "B.Fab")
		)
		(fp_line
			(start -0.67945 0.3048)
			(end -0.120396 0.3048)
			(stroke
				(width 0.1)
				(type default)
			)
			(layer "B.Fab")
		)
		(fp_line
			(start -0.12065 -0.3048)
			(end -0.67945 -0.3048)
			(stroke
				(width 0.1)
				(type default)
			)
			(layer "B.Fab")
		)
		(fp_line
			(start -0.12065 -0.2794)
			(end -0.12065 -0.3048)
			(stroke
				(width 0.1)
				(type default)
			)
			(layer "B.Fab")
		)
		(fp_line
			(start -0.120396 0.2794)
			(end 0.12065 0.2794)
			(stroke
				(width 0.1)
				(type default)
			)
			(layer "B.Fab")
		)
		(fp_line
			(start -0.120396 0.3048)
			(end -0.120396 0.2794)
			(stroke
				(width 0.1)
				(type default)
			)
			(layer "B.Fab")
		)
		(fp_line
			(start 0.12065 -0.305054)
			(end 0.12065 -0.2794)
			(stroke
				(width 0.1)
				(type default)
			)
			(layer "B.Fab")
		)
		(fp_line
			(start 0.12065 -0.2794)
			(end -0.12065 -0.2794)
			(stroke
				(width 0.1)
				(type default)
			)
			(layer "B.Fab")
		)
		(fp_line
			(start 0.12065 0.2794)
			(end 0.12065 0.3048)
			(stroke
				(width 0.1)
				(type default)
			)
			(layer "B.Fab")
		)
		(fp_line
			(start 0.12065 0.3048)
			(end 0.67945 0.3048)
			(stroke
				(width 0.1)
				(type default)
			)
			(layer "B.Fab")
		)
		(fp_line
			(start 0.67945 -0.305054)
			(end 0.12065 -0.305054)
			(stroke
				(width 0.1)
				(type default)
			)
			(layer "B.Fab")
		)
		(fp_line
			(start 0.67945 0.3048)
			(end 0.67945 -0.305054)
			(stroke
				(width 0.1)
				(type default)
			)
			(layer "B.Fab")
		)
		(pad "1" smd circle
			(at 0.40005 0 180)
			(size 0 0)
			(layers "B.Cu" "B.Mask" "B.Paste")
			(net "P12V_AUX")
		)
		(pad "2" smd circle
			(at -0.40005 0 180)
			(size 0 0)
			(layers "B.Cu" "B.Mask" "B.Paste")
			(net "HSC_VOSEN")
		)
	)
	(footprint ""
		(layer "B.Cu")
		(at 75.57008 -4.251198 -90)
		(property "Reference" "R3166"
			(at 0 0 90)
			(layer "B.SilkS")
			(hide yes)
			(effects
				(font
					(size 1.27 1.27)
				)
				(justify mirror)
			)
		)
		(property "Value" ""
			(at 0 0 90)
			(layer "B.Fab")
			(effects
				(font
					(size 1.27 1.27)
				)
				(justify mirror)
			)
		)
		(duplicate_pad_numbers_are_jumpers no)
		(fp_line
			(start -0.7874 0.4064)
			(end 0.7874 0.4064)
			(stroke
				(width 0.1524)
				(type default)
			)
			(layer "B.SilkS")
		)
		(fp_line
			(start 0.7874 0.4064)
			(end 0.7874 -0.4064)
			(stroke
				(width 0.1524)
				(type default)
			)
			(layer "B.SilkS")
		)
		(fp_line
			(start -0.7874 -0.4064)
			(end -0.7874 0.4064)
			(stroke
				(width 0.1524)
				(type default)
			)
			(layer "B.SilkS")
		)
		(fp_line
			(start 0.7874 -0.4064)
			(end -0.7874 -0.4064)
			(stroke
				(width 0.1524)
				(type default)
			)
			(layer "B.SilkS")
		)
		(fp_line
			(start -0.67945 0.3048)
			(end -0.120396 0.3048)
			(stroke
				(width 0.1)
				(type default)
			)
			(layer "B.Fab")
		)
		(fp_line
			(start -0.120396 0.3048)
			(end -0.120396 0.2794)
			(stroke
				(width 0.1)
				(type default)
			)
			(layer "B.Fab")
		)
		(fp_line
			(start 0.12065 0.3048)
			(end 0.67945 0.3048)
			(stroke
				(width 0.1)
				(type default)
			)
			(layer "B.Fab")
		)
		(fp_line
			(start 0.67945 0.3048)
			(end 0.67945 -0.305054)
			(stroke
				(width 0.1)
				(type default)
			)
			(layer "B.Fab")
		)
		(fp_line
			(start -0.120396 0.2794)
			(end 0.12065 0.2794)
			(stroke
				(width 0.1)
				(type default)
			)
			(layer "B.Fab")
		)
		(fp_line
			(start 0.12065 0.2794)
			(end 0.12065 0.3048)
			(stroke
				(width 0.1)
				(type default)
			)
			(layer "B.Fab")
		)
		(fp_line
			(start -0.12065 -0.2794)
			(end -0.12065 -0.3048)
			(stroke
				(width 0.1)
				(type default)
			)
			(layer "B.Fab")
		)
		(fp_line
			(start 0.12065 -0.2794)
			(end -0.12065 -0.2794)
			(stroke
				(width 0.1)
				(type default)
			)
			(layer "B.Fab")
		)
		(fp_line
			(start -0.67945 -0.3048)
			(end -0.67945 0.3048)
			(stroke
				(width 0.1)
				(type default)
			)
			(layer "B.Fab")
		)
		(fp_line
			(start -0.12065 -0.3048)
			(end -0.67945 -0.3048)
			(stroke
				(width 0.1)
				(type default)
			)
			(layer "B.Fab")
		)
		(fp_line
			(start 0.12065 -0.305054)
			(end 0.12065 -0.2794)
			(stroke
				(width 0.1)
				(type default)
			)
			(layer "B.Fab")
		)
		(fp_line
			(start 0.67945 -0.305054)
			(end 0.12065 -0.305054)
			(stroke
				(width 0.1)
				(type default)
			)
			(layer "B.Fab")
		)
		(pad "1" smd circle
			(at 0.40005 0 90)
			(size 0 0)
			(layers "B.Cu" "B.Mask" "B.Paste")
			(net "P3V3_OCP_V3_2")
		)
		(pad "2" smd circle
			(at -0.40005 0 90)
			(size 0 0)
			(layers "B.Cu" "B.Mask" "B.Paste")
			(net "OCP_V3_2_ID1")
		)
	)
)
